(kicad_pcb
	(version 20241229)
	(generator "pcbnew")
	(generator_version "9.0")
	(general
		(thickness 1.62)
		(legacy_teardrops no)
	)
	(paper "A3")
	(title_block
		(title "COM Express 7 Baseboard")
		(date "2025-02-04")
		(rev "1.1.2")
		(company "Antmicro Ltd")
		(comment 1 "www.antmicro.com")
		(comment 9 "footprints 677-682 of 802")
	)
	(layers
		(0 "F.Cu" signal)
		(4 "In1.Cu" signal)
		(6 "In2.Cu" signal)
		(8 "In3.Cu" signal)
		(10 "In4.Cu" signal)
		(12 "In5.Cu" signal)
		(14 "In6.Cu" signal)
		(2 "B.Cu" signal)
		(9 "F.Adhes" user "F.Adhesive")
		(11 "B.Adhes" user "B.Adhesive")
		(13 "F.Paste" user)
		(15 "B.Paste" user)
		(5 "F.SilkS" user "F.Silkscreen")
		(7 "B.SilkS" user "B.Silkscreen")
		(1 "F.Mask" user)
		(3 "B.Mask" user)
		(17 "Dwgs.User" user "User.Drawings")
		(19 "Cmts.User" user "User.Comments")
		(21 "Eco1.User" user "User.Eco1")
		(23 "Eco2.User" user "User.Eco2")
		(25 "Edge.Cuts" user)
		(27 "Margin" user)
		(31 "F.CrtYd" user "F.Courtyard")
		(29 "B.CrtYd" user "B.Courtyard")
		(35 "F.Fab" user)
		(33 "B.Fab" user)
	)
	(footprint "antmicro-footprints:TP_SMD_0.75mm"
		(layer "B.Cu")
		(at 197.075 157.625 180)
		(property "Reference" "TP18"
			(at -3.425 -0.375 0)
			(layer "B.SilkS")
			(effects
				(font
					(size 0.7 0.7)
					(thickness 0.15)
				)
				(justify left bottom mirror)
			)
		)
		(property "Value" "TP_0.75mm_SMD"
			(at 3.225 -53.865 0)
			(layer "B.Fab")
			(hide yes)
			(effects
				(font
					(size 0.7 0.7)
					(thickness 0.15)
				)
				(justify left bottom mirror)
			)
		)
		(property "Author" "Antmicro"
			(at 429.2 321.82 0)
			(layer "B.Fab")
			(hide yes)
			(effects
				(font
					(size 1 1)
					(thickness 0.15)
				)
				(justify mirror)
			)
		)
		(property "License" "Apache-2.0"
			(at 429.2 321.82 0)
			(layer "B.Fab")
			(hide yes)
			(effects
				(font
					(size 1 1)
					(thickness 0.15)
				)
				(justify mirror)
			)
		)
		(property "MPN" ""
			(at 429.2 321.82 0)
			(layer "B.Fab")
			(hide yes)
			(effects
				(font
					(size 1 1)
					(thickness 0.15)
				)
				(justify mirror)
			)
		)
		(property "Manufacturer" ""
			(at 429.2 321.82 0)
			(layer "B.Fab")
			(hide yes)
			(effects
				(font
					(size 1 1)
					(thickness 0.15)
				)
				(justify mirror)
			)
		)
		(property "Public" "False"
			(at 429.2 321.82 0)
			(layer "B.Fab")
			(hide yes)
			(effects
				(font
					(size 1 1)
					(thickness 0.15)
				)
				(justify mirror)
			)
		)
		(sheetname "Com Express 7 Interfaces")
		(sheetfile "com_express_7_interfaces.kicad_sch")
		(attr exclude_from_pos_files exclude_from_bom)
		(fp_circle
			(center 0 0)
			(end 0.475 0)
			(stroke
				(width 0.05)
				(type default)
			)
			(fill no)
			(layer "B.CrtYd")
		)
		(pad "1" smd circle
			(at 0 0 180)
			(size 0.75 0.75)
			(layers "B.Cu" "B.Mask")
			(net 426 "Net-(J12K-10G_SDP0)")
			(pinfunction "1")
			(pintype "passive")
			(teardrops
				(best_length_ratio 0.4)
				(max_length 1)
				(best_width_ratio 0.9)
				(max_width 2)
				(curved_edges yes)
				(filter_ratio 0.9)
				(enabled yes)
				(allow_two_segments yes)
				(prefer_zone_connections yes)
			)
		)
	)
	(footprint "antmicro-footprints:TP_SMD_0.75mm"
		(layer "B.Cu")
		(at 122.3 150.21 180)
		(property "Reference" "TP51"
			(at -0.45 -0.35 90)
			(layer "B.SilkS")
			(effects
				(font
					(size 0.7 0.7)
					(thickness 0.15)
				)
				(justify left bottom mirror)
			)
		)
		(property "Value" "TP_0.75mm_SMD"
			(at 0 -1.2 0)
			(layer "B.Fab")
			(effects
				(font
					(size 0.7 0.7)
					(thickness 0.15)
				)
				(justify left bottom mirror)
			)
		)
		(property "Author" "Antmicro"
			(at 244.6 300.42 0)
			(layer "B.Fab")
			(hide yes)
			(effects
				(font
					(size 1 1)
					(thickness 0.15)
				)
				(justify mirror)
			)
		)
		(property "License" "Apache-2.0"
			(at 244.6 300.42 0)
			(layer "B.Fab")
			(hide yes)
			(effects
				(font
					(size 1 1)
					(thickness 0.15)
				)
				(justify mirror)
			)
		)
		(property "MPN" ""
			(at 244.6 300.42 0)
			(layer "B.Fab")
			(hide yes)
			(effects
				(font
					(size 1 1)
					(thickness 0.15)
				)
				(justify mirror)
			)
		)
		(property "Manufacturer" ""
			(at 244.6 300.42 0)
			(layer "B.Fab")
			(hide yes)
			(effects
				(font
					(size 1 1)
					(thickness 0.15)
				)
				(justify mirror)
			)
		)
		(property "Public" "False"
			(at 244.6 300.42 0)
			(layer "B.Fab")
			(hide yes)
			(effects
				(font
					(size 1 1)
					(thickness 0.15)
				)
				(justify mirror)
			)
		)
		(sheetname "PCIe redriver")
		(sheetfile "pcie_redriver.kicad_sch")
		(attr exclude_from_pos_files exclude_from_bom)
		(fp_circle
			(center 0 0)
			(end 0.475 0)
			(stroke
				(width 0.05)
				(type default)
			)
			(fill no)
			(layer "B.CrtYd")
		)
		(pad "1" smd circle
			(at 0 0 180)
			(size 0.75 0.75)
			(layers "B.Cu" "B.Mask")
			(net 714 "Net-(U39-I2C_{DONE})")
			(pinfunction "1")
			(pintype "passive")
			(teardrops
				(best_length_ratio 0.4)
				(max_length 1)
				(best_width_ratio 0.9)
				(max_width 2)
				(curved_edges yes)
				(filter_ratio 0.9)
				(enabled yes)
				(allow_two_segments yes)
				(prefer_zone_connections yes)
			)
		)
	)
	(footprint "antmicro-footprints:R_0402_1005Metric"
		(layer "B.Cu")
		(at 313.024999 106.15 -90)
		(descr "Resistor SMD 0402")
		(tags "resistor SMD 0402")
		(property "Reference" "R96"
			(at 0.81 -0.425001 90)
			(layer "B.SilkS")
			(effects
				(font
					(size 0.7 0.7)
					(thickness 0.15)
				)
				(justify left bottom mirror)
			)
		)
		(property "Value" "R_10k_0402"
			(at -1.011843 -1.772046 90)
			(layer "B.Fab")
			(effects
				(font
					(size 0.7 0.7)
					(thickness 0.15)
				)
				(justify left bottom mirror)
			)
		)
		(property "Datasheet" "https://www.bourns.com/docs/product-datasheets/cr.pdf"
			(at 0 0 270)
			(layer "F.Fab")
			(hide yes)
			(effects
				(font
					(size 1.27 1.27)
					(thickness 0.15)
				)
			)
		)
		(property "Author" "Antmicro"
			(at 206.874999 419.174999 0)
			(layer "B.Fab")
			(hide yes)
			(effects
				(font
					(size 1 1)
					(thickness 0.15)
				)
				(justify mirror)
			)
		)
		(property "License" "Apache-2.0"
			(at 206.874999 419.174999 0)
			(layer "B.Fab")
			(hide yes)
			(effects
				(font
					(size 1 1)
					(thickness 0.15)
				)
				(justify mirror)
			)
		)
		(property "MPN" "CR0402-FX-1002GLF"
			(at 206.874999 419.174999 0)
			(layer "B.Fab")
			(hide yes)
			(effects
				(font
					(size 1 1)
					(thickness 0.15)
				)
				(justify mirror)
			)
		)
		(property "Manufacturer" "Bourns"
			(at 206.874999 419.174999 0)
			(layer "B.Fab")
			(hide yes)
			(effects
				(font
					(size 1 1)
					(thickness 0.15)
				)
				(justify mirror)
			)
		)
		(property "Public" "False"
			(at 206.874999 419.174999 0)
			(layer "B.Fab")
			(hide yes)
			(effects
				(font
					(size 1 1)
					(thickness 0.15)
				)
				(justify mirror)
			)
		)
		(property "Tolerance" "1%"
			(at 206.874999 419.174999 0)
			(layer "B.Fab")
			(hide yes)
			(effects
				(font
					(size 1 1)
					(thickness 0.15)
				)
				(justify mirror)
			)
		)
		(property "Val" "10k"
			(at 206.874999 419.174999 0)
			(layer "B.Fab")
			(hide yes)
			(effects
				(font
					(size 1 1)
					(thickness 0.15)
				)
				(justify mirror)
			)
		)
		(sheetname "Power")
		(sheetfile "power.kicad_sch")
		(attr smd)
		(fp_rect
			(start -0.925 0.47)
			(end 0.925 -0.47)
			(stroke
				(width 0.05)
				(type default)
			)
			(fill no)
			(layer "B.CrtYd")
		)
		(fp_rect
			(start -0.5 0.25)
			(end 0.5 -0.25)
			(stroke
				(width 0.15)
				(type solid)
			)
			(fill no)
			(layer "B.Fab")
		)
		(pad "1" smd roundrect
			(at -0.48 0 270)
			(size 0.59 0.64)
			(layers "B.Cu" "B.Mask" "B.Paste")
			(roundrect_rratio 0.25)
			(net 889 "/Power/PG_{3V3}")
			(pintype "passive")
			(teardrops
				(best_length_ratio 0.2)
				(max_length 1)
				(best_width_ratio 0.9)
				(max_width 2)
				(curved_edges yes)
				(filter_ratio 0.9)
				(enabled yes)
				(allow_two_segments yes)
				(prefer_zone_connections yes)
			)
		)
		(pad "2" smd roundrect
			(at 0.48 0 270)
			(size 0.59 0.64)
			(layers "B.Cu" "B.Mask" "B.Paste")
			(roundrect_rratio 0.25)
			(net 64 "Net-(U19-V_{CC})")
			(pintype "passive")
			(teardrops
				(best_length_ratio 0.2)
				(max_length 1)
				(best_width_ratio 0.9)
				(max_width 2)
				(curved_edges yes)
				(filter_ratio 0.9)
				(enabled yes)
				(allow_two_segments yes)
				(prefer_zone_connections yes)
			)
		)
	)
	(footprint "antmicro-footprints:R_0402_1005Metric"
		(layer "B.Cu")
		(at 123.4 107.81)
		(descr "Resistor SMD 0402")
		(tags "resistor SMD 0402")
		(property "Reference" "R10"
			(at 0.8 0.45 0)
			(layer "B.SilkS")
			(effects
				(font
					(size 0.7 0.7)
					(thickness 0.15)
				)
				(justify right bottom mirror)
			)
		)
		(property "Value" "R_470R_0402"
			(at -1.011843 -1.772047 0)
			(layer "B.Fab")
			(effects
				(font
					(size 0.7 0.7)
					(thickness 0.15)
				)
				(justify right bottom mirror)
			)
		)
		(property "Datasheet" "https://www.bourns.com/docs/product-datasheets/cr.pdf"
			(at 0 0 0)
			(layer "F.Fab")
			(hide yes)
			(effects
				(font
					(size 1.27 1.27)
					(thickness 0.15)
				)
			)
		)
		(property "Author" "Antmicro"
			(at 0 0 0)
			(layer "B.Fab")
			(hide yes)
			(effects
				(font
					(size 1 1)
					(thickness 0.15)
				)
				(justify mirror)
			)
		)
		(property "License" "Apache-2.0"
			(at 0 0 0)
			(layer "B.Fab")
			(hide yes)
			(effects
				(font
					(size 1 1)
					(thickness 0.15)
				)
				(justify mirror)
			)
		)
		(property "MPN" "CR0402-FX-4700GLF"
			(at 0 0 0)
			(layer "B.Fab")
			(hide yes)
			(effects
				(font
					(size 1 1)
					(thickness 0.15)
				)
				(justify mirror)
			)
		)
		(property "Manufacturer" "Bourns"
			(at 0 0 0)
			(layer "B.Fab")
			(hide yes)
			(effects
				(font
					(size 1 1)
					(thickness 0.15)
				)
				(justify mirror)
			)
		)
		(property "Public" "False"
			(at 0 0 0)
			(layer "B.Fab")
			(hide yes)
			(effects
				(font
					(size 1 1)
					(thickness 0.15)
				)
				(justify mirror)
			)
		)
		(property "Tolerance" "1%"
			(at 0 0 0)
			(layer "B.Fab")
			(hide yes)
			(effects
				(font
					(size 1 1)
					(thickness 0.15)
				)
				(justify mirror)
			)
		)
		(property "Val" "470R"
			(at 0 0 0)
			(layer "B.Fab")
			(hide yes)
			(effects
				(font
					(size 1 1)
					(thickness 0.15)
				)
				(justify mirror)
			)
		)
		(sheetname "2xUSB3.0+RJ45")
		(sheetfile "usb3+rj45.kicad_sch")
		(attr smd dnp)
		(fp_rect
			(start -0.925 0.47)
			(end 0.925 -0.47)
			(stroke
				(width 0.05)
				(type default)
			)
			(fill no)
			(layer "B.CrtYd")
		)
		(fp_rect
			(start -0.5 0.25)
			(end 0.5 -0.25)
			(stroke
				(width 0.15)
				(type solid)
			)
			(fill no)
			(layer "B.Fab")
		)
		(pad "1" smd roundrect
			(at -0.48 0)
			(size 0.59 0.64)
			(layers "B.Cu" "B.Mask" "B.Paste")
			(roundrect_rratio 0.25)
			(net 157 "Net-(J1A-LED_D4)")
			(pintype "passive")
			(teardrops
				(best_length_ratio 0.2)
				(max_length 1)
				(best_width_ratio 0.9)
				(max_width 2)
				(curved_edges yes)
				(filter_ratio 0.9)
				(enabled yes)
				(allow_two_segments yes)
				(prefer_zone_connections yes)
			)
		)
		(pad "2" smd roundrect
			(at 0.48 0)
			(size 0.59 0.64)
			(layers "B.Cu" "B.Mask" "B.Paste")
			(roundrect_rratio 0.25)
			(net 2 "+3V3")
			(pintype "passive")
			(teardrops
				(best_length_ratio 0.2)
				(max_length 1)
				(best_width_ratio 0.9)
				(max_width 2)
				(curved_edges yes)
				(filter_ratio 0.9)
				(enabled yes)
				(allow_two_segments yes)
				(prefer_zone_connections yes)
			)
		)
	)
	(footprint "antmicro-footprints:TP_SMD_0.75mm"
		(layer "B.Cu")
		(at 183.5 170.8 90)
		(property "Reference" "TP36"
			(at -0.5 0.6 180)
			(layer "B.SilkS")
			(effects
				(font
					(size 0.7 0.7)
					(thickness 0.15)
				)
				(justify right bottom mirror)
			)
		)
		(property "Value" "TP_0.75mm_SMD"
			(at 0 -1.2 90)
			(layer "B.Fab")
			(effects
				(font
					(size 0.7 0.7)
					(thickness 0.15)
				)
				(justify right bottom mirror)
			)
		)
		(property "Author" "Antmicro"
			(at 371.06 -72.24 0)
			(layer "B.Fab")
			(hide yes)
			(effects
				(font
					(size 1 1)
					(thickness 0.15)
				)
				(justify mirror)
			)
		)
		(property "License" "Apache-2.0"
			(at 371.06 -72.24 0)
			(layer "B.Fab")
			(hide yes)
			(effects
				(font
					(size 1 1)
					(thickness 0.15)
				)
				(justify mirror)
			)
		)
		(property "MPN" ""
			(at 371.06 -72.24 0)
			(layer "B.Fab")
			(hide yes)
			(effects
				(font
					(size 1 1)
					(thickness 0.15)
				)
				(justify mirror)
			)
		)
		(property "Manufacturer" ""
			(at 371.06 -72.24 0)
			(layer "B.Fab")
			(hide yes)
			(effects
				(font
					(size 1 1)
					(thickness 0.15)
				)
				(justify mirror)
			)
		)
		(property "Public" "False"
			(at 371.06 -72.24 0)
			(layer "B.Fab")
			(hide yes)
			(effects
				(font
					(size 1 1)
					(thickness 0.15)
				)
				(justify mirror)
			)
		)
		(sheetname "Com Express 7 MGMT")
		(sheetfile "com_express_7_mgmt.kicad_sch")
		(attr exclude_from_pos_files exclude_from_bom)
		(fp_circle
			(center 0 0)
			(end 0.475 0)
			(stroke
				(width 0.05)
				(type default)
			)
			(fill no)
			(layer "B.CrtYd")
		)
		(pad "1" smd circle
			(at 0 0 90)
			(size 0.75 0.75)
			(layers "B.Cu" "B.Mask")
			(net 300 "Net-(J12D-~{SUS_S4})")
			(pinfunction "1")
			(pintype "passive")
			(teardrops
				(best_length_ratio 0.4)
				(max_length 1)
				(best_width_ratio 0.9)
				(max_width 2)
				(curved_edges yes)
				(filter_ratio 0.9)
				(enabled yes)
				(allow_two_segments yes)
				(prefer_zone_connections yes)
			)
		)
	)
	(footprint "antmicro-footprints:R_0402_1005Metric"
		(layer "B.Cu")
		(at 144.05 169.16 -90)
		(descr "Resistor SMD 0402")
		(tags "resistor SMD 0402")
		(property "Reference" "R55"
			(at -3.9 13.5 90)
			(layer "B.SilkS")
			(effects
				(font
					(size 0.7 0.7)
					(thickness 0.15)
				)
				(justify left bottom mirror)
			)
		)
		(property "Value" "R_1k_0402"
			(at -1.011843 -1.772047 90)
			(layer "B.Fab")
			(effects
				(font
					(size 0.7 0.7)
					(thickness 0.15)
				)
				(justify left bottom mirror)
			)
		)
		(property "Datasheet" "https://www.bourns.com/docs/product-datasheets/cr.pdf"
			(at 0 0 270)
			(layer "F.Fab")
			(hide yes)
			(effects
				(font
					(size 1.27 1.27)
					(thickness 0.15)
				)
			)
		)
		(property "Author" "Antmicro"
			(at -25.11 313.21 0)
			(layer "B.Fab")
			(hide yes)
			(effects
				(font
					(size 1 1)
					(thickness 0.15)
				)
				(justify mirror)
			)
		)
		(property "License" "Apache-2.0"
			(at -25.11 313.21 0)
			(layer "B.Fab")
			(hide yes)
			(effects
				(font
					(size 1 1)
					(thickness 0.15)
				)
				(justify mirror)
			)
		)
		(property "MPN" "CR0402-FX-1001GLF"
			(at -25.11 313.21 0)
			(layer "B.Fab")
			(hide yes)
			(effects
				(font
					(size 1 1)
					(thickness 0.15)
				)
				(justify mirror)
			)
		)
		(property "Manufacturer" "Bourns"
			(at -25.11 313.21 0)
			(layer "B.Fab")
			(hide yes)
			(effects
				(font
					(size 1 1)
					(thickness 0.15)
				)
				(justify mirror)
			)
		)
		(property "Public" "False"
			(at -25.11 313.21 0)
			(layer "B.Fab")
			(hide yes)
			(effects
				(font
					(size 1 1)
					(thickness 0.15)
				)
				(justify mirror)
			)
		)
		(property "Tolerance" "1%"
			(at -25.11 313.21 0)
			(layer "B.Fab")
			(hide yes)
			(effects
				(font
					(size 1 1)
					(thickness 0.15)
				)
				(justify mirror)
			)
		)
		(property "Val" "1k"
			(at -25.11 313.21 0)
			(layer "B.Fab")
			(hide yes)
			(effects
				(font
					(size 1 1)
					(thickness 0.15)
				)
				(justify mirror)
			)
		)
		(sheetname "2xSFP+")
		(sheetfile "2xSFP+.kicad_sch")
		(attr smd)
		(fp_rect
			(start -0.925 0.47)
			(end 0.925 -0.47)
			(stroke
				(width 0.05)
				(type default)
			)
			(fill no)
			(layer "B.CrtYd")
		)
		(fp_rect
			(start -0.5 0.25)
			(end 0.5 -0.25)
			(stroke
				(width 0.15)
				(type solid)
			)
			(fill no)
			(layer "B.Fab")
		)
		(pad "1" smd roundrect
			(at -0.48 0 270)
			(size 0.59 0.64)
			(layers "B.Cu" "B.Mask" "B.Paste")
			(roundrect_rratio 0.25)
			(net 166 "Net-(J2A-MOD_{ABS})")
			(pintype "passive")
			(teardrops
				(best_length_ratio 0.2)
				(max_length 1)
				(best_width_ratio 0.9)
				(max_width 2)
				(curved_edges yes)
				(filter_ratio 0.9)
				(enabled yes)
				(allow_two_segments yes)
				(prefer_zone_connections yes)
			)
		)
		(pad "2" smd roundrect
			(at 0.48 0 270)
			(size 0.59 0.64)
			(layers "B.Cu" "B.Mask" "B.Paste")
			(roundrect_rratio 0.25)
			(net 2 "+3V3")
			(pintype "passive")
			(teardrops
				(best_length_ratio 0.2)
				(max_length 1)
				(best_width_ratio 0.9)
				(max_width 2)
				(curved_edges yes)
				(filter_ratio 0.9)
				(enabled yes)
				(allow_two_segments yes)
				(prefer_zone_connections yes)
			)
		)
	)
)
